(kicad_pcb
	(version 20260206)
	(generator "pcbnew")
	(generator_version "10.0")
	(general
		(thickness 1.6)
		(legacy_teardrops no)
	)
	(paper "A4")
	(title_block
		(title "03242023_DA0F0TMBIJ0_F0T_Motherboard_J_brd_V01_OCP.brd")
		(comment 1 "Grand Teton / footprints 3813-3818 of 6105")
	)
	(layers
		(0 "F.Cu" signal "TOP")
		(4 "In1.Cu" signal "GND")
		(6 "In2.Cu" signal "IN1")
		(8 "In3.Cu" signal "GND1")
		(10 "In4.Cu" signal "IN2")
		(12 "In5.Cu" signal "GND2")
		(14 "In6.Cu" signal "IN3")
		(16 "In7.Cu" signal "GND3")
		(18 "In8.Cu" signal "VCC")
		(20 "In9.Cu" signal "VCC1")
		(22 "In10.Cu" signal "GND4")
		(24 "In11.Cu" signal "IN4")
		(26 "In12.Cu" signal "GND5")
		(28 "In13.Cu" signal "IN5")
		(30 "In14.Cu" signal "GND6")
		(32 "In15.Cu" signal "IN6")
		(34 "In16.Cu" signal "GND7")
		(2 "B.Cu" signal "BOTTOM")
		(9 "F.Adhes" user "F.Adhesive")
		(11 "B.Adhes" user "B.Adhesive")
		(13 "F.Paste" user "Package Geometry/Pastemask Top")
		(15 "B.Paste" user "Package Geometry/Pastemask Bottom")
		(5 "F.SilkS" user "Ref Des/Silkscreen Top")
		(7 "B.SilkS" user "Ref Des/Silkscreen Bottom")
		(1 "F.Mask" user "Board Geometry/Soldermask Top")
		(3 "B.Mask" user "Board Geometry/Soldermask Bottom")
		(17 "Dwgs.User" user "User.Drawings")
		(19 "Cmts.User" user "User.Comments")
		(21 "Eco1.User" user "User.Eco1")
		(23 "Eco2.User" user "User.Eco2")
		(25 "Edge.Cuts" user "Board Geometry/Outline")
		(27 "Margin" user)
		(31 "F.CrtYd" user "Package Geometry/Place Bound Top")
		(29 "B.CrtYd" user "Package Geometry/Place Bound Bottom")
		(35 "F.Fab" user "Ref Des/Assembly Top")
		(33 "B.Fab" user "Ref Des/Assembly Bottom")
	)
	(footprint ""
		(layer "F.Cu")
		(at 391.672572 -76.460604 -90)
		(property "Reference" "PL16"
			(at 0 0 270)
			(layer "F.SilkS")
			(hide yes)
			(effects
				(font
					(size 1.27 1.27)
				)
			)
		)
		(property "Value" ""
			(at 0 0 270)
			(layer "F.Fab")
			(effects
				(font
					(size 1.27 1.27)
				)
			)
		)
		(duplicate_pad_numbers_are_jumpers no)
		(fp_line
			(start -1.27 0.5842)
			(end -1.27 -0.5842)
			(stroke
				(width 0.1524)
				(type default)
			)
			(layer "F.SilkS")
		)
		(fp_line
			(start -0.127 0.5842)
			(end -0.127 -0.5842)
			(stroke
				(width 0.1524)
				(type default)
			)
			(layer "F.SilkS")
		)
		(fp_line
			(start 0.127 0.5842)
			(end 0.127 -0.5842)
			(stroke
				(width 0.1524)
				(type default)
			)
			(layer "F.SilkS")
		)
		(fp_line
			(start 1.27 0.5842)
			(end -1.27 0.5842)
			(stroke
				(width 0.1524)
				(type default)
			)
			(layer "F.SilkS")
		)
		(fp_line
			(start 1.27 0.5842)
			(end 1.27 -0.5842)
			(stroke
				(width 0.1524)
				(type default)
			)
			(layer "F.SilkS")
		)
		(fp_line
			(start -1.27 -0.5588)
			(end -1.27 -0.5842)
			(stroke
				(width 0.1524)
				(type default)
			)
			(layer "F.SilkS")
		)
		(fp_line
			(start -1.27 -0.5842)
			(end 1.27 -0.5842)
			(stroke
				(width 0.1524)
				(type default)
			)
			(layer "F.SilkS")
		)
		(fp_line
			(start -0.9144 0.508)
			(end -0.9144 0.406654)
			(stroke
				(width 0.1)
				(type default)
			)
			(layer "F.Fab")
		)
		(fp_line
			(start 0.9144 0.508)
			(end -0.9144 0.508)
			(stroke
				(width 0.1)
				(type default)
			)
			(layer "F.Fab")
		)
		(fp_line
			(start -1.194308 0.406654)
			(end -1.194308 -0.406654)
			(stroke
				(width 0.1)
				(type default)
			)
			(layer "F.Fab")
		)
		(fp_line
			(start -0.9144 0.406654)
			(end -1.194308 0.406654)
			(stroke
				(width 0.1)
				(type default)
			)
			(layer "F.Fab")
		)
		(fp_line
			(start 0.9144 0.4064)
			(end 0.9144 0.508)
			(stroke
				(width 0.1)
				(type default)
			)
			(layer "F.Fab")
		)
		(fp_line
			(start 1.1938 0.4064)
			(end 0.9144 0.4064)
			(stroke
				(width 0.1)
				(type default)
			)
			(layer "F.Fab")
		)
		(fp_line
			(start -1.194308 -0.406654)
			(end -0.9144 -0.406654)
			(stroke
				(width 0.1)
				(type default)
			)
			(layer "F.Fab")
		)
		(fp_line
			(start -0.9144 -0.406654)
			(end -0.9144 -0.508)
			(stroke
				(width 0.1)
				(type default)
			)
			(layer "F.Fab")
		)
		(fp_line
			(start 0.9144 -0.406654)
			(end 1.1938 -0.406654)
			(stroke
				(width 0.1)
				(type default)
			)
			(layer "F.Fab")
		)
		(fp_line
			(start 1.1938 -0.406654)
			(end 1.1938 0.4064)
			(stroke
				(width 0.1)
				(type default)
			)
			(layer "F.Fab")
		)
		(fp_line
			(start -0.9144 -0.508)
			(end 0.9144 -0.508)
			(stroke
				(width 0.1)
				(type default)
			)
			(layer "F.Fab")
		)
		(fp_line
			(start 0.9144 -0.508)
			(end 0.9144 -0.406654)
			(stroke
				(width 0.1)
				(type default)
			)
			(layer "F.Fab")
		)
		(pad "1" smd rect
			(at -0.7366 0 180)
			(size 0.7112 0.8128)
			(layers "F.Cu" "F.Mask" "F.Paste")
			(net "P12V_AUX")
		)
		(pad "2" smd rect
			(at 0.7366 0 180)
			(size 0.7112 0.8128)
			(layers "F.Cu" "F.Mask" "F.Paste")
			(net "SW_P1V8_PCH_AUX_FLT")
		)
	)
	(footprint ""
		(layer "F.Cu")
		(at 376.8852 -107.183428 180)
		(property "Reference" "R1346"
			(at 0 0 180)
			(layer "F.SilkS")
			(hide yes)
			(effects
				(font
					(size 1.27 1.27)
				)
			)
		)
		(property "Value" ""
			(at 0 0 180)
			(layer "F.Fab")
			(effects
				(font
					(size 1.27 1.27)
				)
			)
		)
		(duplicate_pad_numbers_are_jumpers no)
		(fp_line
			(start 0.7874 0.4064)
			(end -0.7874 0.4064)
			(stroke
				(width 0.1524)
				(type default)
			)
			(layer "F.SilkS")
		)
		(fp_line
			(start 0.7874 -0.4064)
			(end 0.7874 0.4064)
			(stroke
				(width 0.1524)
				(type default)
			)
			(layer "F.SilkS")
		)
		(fp_line
			(start -0.7874 0.4064)
			(end -0.7874 -0.4064)
			(stroke
				(width 0.1524)
				(type default)
			)
			(layer "F.SilkS")
		)
		(fp_line
			(start -0.7874 -0.4064)
			(end 0.7874 -0.4064)
			(stroke
				(width 0.1524)
				(type default)
			)
			(layer "F.SilkS")
		)
		(fp_line
			(start 0.67945 0.3048)
			(end 0.120396 0.3048)
			(stroke
				(width 0.1)
				(type default)
			)
			(layer "F.Fab")
		)
		(fp_line
			(start 0.67945 -0.3048)
			(end 0.67945 0.3048)
			(stroke
				(width 0.1)
				(type default)
			)
			(layer "F.Fab")
		)
		(fp_line
			(start 0.12065 -0.2794)
			(end 0.12065 -0.3048)
			(stroke
				(width 0.1)
				(type default)
			)
			(layer "F.Fab")
		)
		(fp_line
			(start 0.12065 -0.3048)
			(end 0.67945 -0.3048)
			(stroke
				(width 0.1)
				(type default)
			)
			(layer "F.Fab")
		)
		(fp_line
			(start 0.120396 0.3048)
			(end 0.120396 0.2794)
			(stroke
				(width 0.1)
				(type default)
			)
			(layer "F.Fab")
		)
		(fp_line
			(start 0.120396 0.2794)
			(end -0.12065 0.2794)
			(stroke
				(width 0.1)
				(type default)
			)
			(layer "F.Fab")
		)
		(fp_line
			(start -0.12065 0.3048)
			(end -0.67945 0.3048)
			(stroke
				(width 0.1)
				(type default)
			)
			(layer "F.Fab")
		)
		(fp_line
			(start -0.12065 0.2794)
			(end -0.12065 0.3048)
			(stroke
				(width 0.1)
				(type default)
			)
			(layer "F.Fab")
		)
		(fp_line
			(start -0.12065 -0.2794)
			(end 0.12065 -0.2794)
			(stroke
				(width 0.1)
				(type default)
			)
			(layer "F.Fab")
		)
		(fp_line
			(start -0.12065 -0.305054)
			(end -0.12065 -0.2794)
			(stroke
				(width 0.1)
				(type default)
			)
			(layer "F.Fab")
		)
		(fp_line
			(start -0.67945 0.3048)
			(end -0.67945 -0.305054)
			(stroke
				(width 0.1)
				(type default)
			)
			(layer "F.Fab")
		)
		(fp_line
			(start -0.67945 -0.305054)
			(end -0.12065 -0.305054)
			(stroke
				(width 0.1)
				(type default)
			)
			(layer "F.Fab")
		)
		(pad "1" smd circle
			(at -0.40005 0 180)
			(size 0 0)
			(layers "F.Cu" "F.Mask" "F.Paste")
			(net "P0V7_JTAG_VREF_2")
		)
		(pad "2" smd circle
			(at 0.40005 0 180)
			(size 0 0)
			(layers "F.Cu" "F.Mask" "F.Paste")
			(net "GND")
		)
	)
	(footprint ""
		(layer "F.Cu")
		(at 139.586208 -347.520514 -90)
		(property "Reference" "PC487"
			(at 0 0 270)
			(layer "F.SilkS")
			(hide yes)
			(effects
				(font
					(size 1.27 1.27)
				)
			)
		)
		(property "Value" ""
			(at 0 0 270)
			(layer "F.Fab")
			(effects
				(font
					(size 1.27 1.27)
				)
			)
		)
		(duplicate_pad_numbers_are_jumpers no)
		(fp_line
			(start -0.7874 0.4064)
			(end -0.7874 -0.4064)
			(stroke
				(width 0.1524)
				(type default)
			)
			(layer "F.SilkS")
		)
		(fp_line
			(start 0.7874 0.4064)
			(end -0.7874 0.4064)
			(stroke
				(width 0.1524)
				(type default)
			)
			(layer "F.SilkS")
		)
		(fp_line
			(start -0.7874 -0.4064)
			(end 0.7874 -0.4064)
			(stroke
				(width 0.1524)
				(type default)
			)
			(layer "F.SilkS")
		)
		(fp_line
			(start 0.7874 -0.4064)
			(end 0.7874 0.4064)
			(stroke
				(width 0.1524)
				(type default)
			)
			(layer "F.SilkS")
		)
		(fp_line
			(start -0.67945 0.3048)
			(end -0.67945 -0.305054)
			(stroke
				(width 0.1)
				(type default)
			)
			(layer "F.Fab")
		)
		(fp_line
			(start -0.12065 0.3048)
			(end -0.67945 0.3048)
			(stroke
				(width 0.1)
				(type default)
			)
			(layer "F.Fab")
		)
		(fp_line
			(start 0.120396 0.3048)
			(end 0.120396 0.2794)
			(stroke
				(width 0.1)
				(type default)
			)
			(layer "F.Fab")
		)
		(fp_line
			(start 0.67945 0.3048)
			(end 0.120396 0.3048)
			(stroke
				(width 0.1)
				(type default)
			)
			(layer "F.Fab")
		)
		(fp_line
			(start -0.12065 0.2794)
			(end -0.12065 0.3048)
			(stroke
				(width 0.1)
				(type default)
			)
			(layer "F.Fab")
		)
		(fp_line
			(start 0.120396 0.2794)
			(end -0.12065 0.2794)
			(stroke
				(width 0.1)
				(type default)
			)
			(layer "F.Fab")
		)
		(fp_line
			(start -0.12065 -0.2794)
			(end 0.12065 -0.2794)
			(stroke
				(width 0.1)
				(type default)
			)
			(layer "F.Fab")
		)
		(fp_line
			(start 0.12065 -0.2794)
			(end 0.12065 -0.3048)
			(stroke
				(width 0.1)
				(type default)
			)
			(layer "F.Fab")
		)
		(fp_line
			(start 0.12065 -0.3048)
			(end 0.67945 -0.3048)
			(stroke
				(width 0.1)
				(type default)
			)
			(layer "F.Fab")
		)
		(fp_line
			(start 0.67945 -0.3048)
			(end 0.67945 0.3048)
			(stroke
				(width 0.1)
				(type default)
			)
			(layer "F.Fab")
		)
		(fp_line
			(start -0.67945 -0.305054)
			(end -0.12065 -0.305054)
			(stroke
				(width 0.1)
				(type default)
			)
			(layer "F.Fab")
		)
		(fp_line
			(start -0.12065 -0.305054)
			(end -0.12065 -0.2794)
			(stroke
				(width 0.1)
				(type default)
			)
			(layer "F.Fab")
		)
		(pad "1" smd circle
			(at -0.40005 0 270)
			(size 0 0)
			(layers "F.Cu" "F.Mask" "F.Paste")
			(net "SW_PVCCIN_CPU1_BOOT8_R")
		)
		(pad "2" smd circle
			(at 0.40005 0 270)
			(size 0 0)
			(layers "F.Cu" "F.Mask" "F.Paste")
			(net "SW_PVCCIN_CPU1_BOOTR8")
		)
	)
	(footprint ""
		(layer "F.Cu")
		(at 102.39375 -360.934762 -90)
		(property "Reference" "R307"
			(at 0 0 270)
			(layer "F.SilkS")
			(hide yes)
			(effects
				(font
					(size 1.27 1.27)
				)
			)
		)
		(property "Value" ""
			(at 0 0 270)
			(layer "F.Fab")
			(effects
				(font
					(size 1.27 1.27)
				)
			)
		)
		(duplicate_pad_numbers_are_jumpers no)
		(fp_line
			(start -0.7874 0.4064)
			(end -0.7874 -0.4064)
			(stroke
				(width 0.1524)
				(type default)
			)
			(layer "F.SilkS")
		)
		(fp_line
			(start 0.7874 0.4064)
			(end -0.7874 0.4064)
			(stroke
				(width 0.1524)
				(type default)
			)
			(layer "F.SilkS")
		)
		(fp_line
			(start -0.7874 -0.4064)
			(end 0.7874 -0.4064)
			(stroke
				(width 0.1524)
				(type default)
			)
			(layer "F.SilkS")
		)
		(fp_line
			(start 0.7874 -0.4064)
			(end 0.7874 0.4064)
			(stroke
				(width 0.1524)
				(type default)
			)
			(layer "F.SilkS")
		)
		(fp_line
			(start -0.67945 0.3048)
			(end -0.67945 -0.305054)
			(stroke
				(width 0.1)
				(type default)
			)
			(layer "F.Fab")
		)
		(fp_line
			(start -0.12065 0.3048)
			(end -0.67945 0.3048)
			(stroke
				(width 0.1)
				(type default)
			)
			(layer "F.Fab")
		)
		(fp_line
			(start 0.120396 0.3048)
			(end 0.120396 0.2794)
			(stroke
				(width 0.1)
				(type default)
			)
			(layer "F.Fab")
		)
		(fp_line
			(start 0.67945 0.3048)
			(end 0.120396 0.3048)
			(stroke
				(width 0.1)
				(type default)
			)
			(layer "F.Fab")
		)
		(fp_line
			(start -0.12065 0.2794)
			(end -0.12065 0.3048)
			(stroke
				(width 0.1)
				(type default)
			)
			(layer "F.Fab")
		)
		(fp_line
			(start 0.120396 0.2794)
			(end -0.12065 0.2794)
			(stroke
				(width 0.1)
				(type default)
			)
			(layer "F.Fab")
		)
		(fp_line
			(start -0.12065 -0.2794)
			(end 0.12065 -0.2794)
			(stroke
				(width 0.1)
				(type default)
			)
			(layer "F.Fab")
		)
		(fp_line
			(start 0.12065 -0.2794)
			(end 0.12065 -0.3048)
			(stroke
				(width 0.1)
				(type default)
			)
			(layer "F.Fab")
		)
		(fp_line
			(start 0.12065 -0.3048)
			(end 0.67945 -0.3048)
			(stroke
				(width 0.1)
				(type default)
			)
			(layer "F.Fab")
		)
		(fp_line
			(start 0.67945 -0.3048)
			(end 0.67945 0.3048)
			(stroke
				(width 0.1)
				(type default)
			)
			(layer "F.Fab")
		)
		(fp_line
			(start -0.67945 -0.305054)
			(end -0.12065 -0.305054)
			(stroke
				(width 0.1)
				(type default)
			)
			(layer "F.Fab")
		)
		(fp_line
			(start -0.12065 -0.305054)
			(end -0.12065 -0.2794)
			(stroke
				(width 0.1)
				(type default)
			)
			(layer "F.Fab")
		)
		(pad "1" smd circle
			(at -0.40005 0 270)
			(size 0 0)
			(layers "F.Cu" "F.Mask" "F.Paste")
			(net "P3V3_AUX")
		)
		(pad "2" smd circle
			(at 0.40005 0 270)
			(size 0 0)
			(layers "F.Cu" "F.Mask" "F.Paste")
			(net "PWRGD_PVCCIN_CPU1_R")
		)
	)
	(footprint ""
		(layer "F.Cu")
		(at 428.226474 -124.02566 180)
		(property "Reference" "PC631"
			(at 0 0 180)
			(layer "F.SilkS")
			(hide yes)
			(effects
				(font
					(size 1.27 1.27)
				)
			)
		)
		(property "Value" ""
			(at 0 0 180)
			(layer "F.Fab")
			(effects
				(font
					(size 1.27 1.27)
				)
			)
		)
		(duplicate_pad_numbers_are_jumpers no)
		(fp_line
			(start 0.7874 0.4064)
			(end -0.7874 0.4064)
			(stroke
				(width 0.1524)
				(type default)
			)
			(layer "F.SilkS")
		)
		(fp_line
			(start 0.7874 -0.4064)
			(end 0.7874 0.4064)
			(stroke
				(width 0.1524)
				(type default)
			)
			(layer "F.SilkS")
		)
		(fp_line
			(start -0.7874 0.4064)
			(end -0.7874 -0.4064)
			(stroke
				(width 0.1524)
				(type default)
			)
			(layer "F.SilkS")
		)
		(fp_line
			(start -0.7874 -0.4064)
			(end 0.7874 -0.4064)
			(stroke
				(width 0.1524)
				(type default)
			)
			(layer "F.SilkS")
		)
		(fp_line
			(start 0.67945 0.3048)
			(end 0.120396 0.3048)
			(stroke
				(width 0.1)
				(type default)
			)
			(layer "F.Fab")
		)
		(fp_line
			(start 0.67945 -0.3048)
			(end 0.67945 0.3048)
			(stroke
				(width 0.1)
				(type default)
			)
			(layer "F.Fab")
		)
		(fp_line
			(start 0.12065 -0.2794)
			(end 0.12065 -0.3048)
			(stroke
				(width 0.1)
				(type default)
			)
			(layer "F.Fab")
		)
		(fp_line
			(start 0.12065 -0.3048)
			(end 0.67945 -0.3048)
			(stroke
				(width 0.1)
				(type default)
			)
			(layer "F.Fab")
		)
		(fp_line
			(start 0.120396 0.3048)
			(end 0.120396 0.2794)
			(stroke
				(width 0.1)
				(type default)
			)
			(layer "F.Fab")
		)
		(fp_line
			(start 0.120396 0.2794)
			(end -0.12065 0.2794)
			(stroke
				(width 0.1)
				(type default)
			)
			(layer "F.Fab")
		)
		(fp_line
			(start -0.12065 0.3048)
			(end -0.67945 0.3048)
			(stroke
				(width 0.1)
				(type default)
			)
			(layer "F.Fab")
		)
		(fp_line
			(start -0.12065 0.2794)
			(end -0.12065 0.3048)
			(stroke
				(width 0.1)
				(type default)
			)
			(layer "F.Fab")
		)
		(fp_line
			(start -0.12065 -0.2794)
			(end 0.12065 -0.2794)
			(stroke
				(width 0.1)
				(type default)
			)
			(layer "F.Fab")
		)
		(fp_line
			(start -0.12065 -0.305054)
			(end -0.12065 -0.2794)
			(stroke
				(width 0.1)
				(type default)
			)
			(layer "F.Fab")
		)
		(fp_line
			(start -0.67945 0.3048)
			(end -0.67945 -0.305054)
			(stroke
				(width 0.1)
				(type default)
			)
			(layer "F.Fab")
		)
		(fp_line
			(start -0.67945 -0.305054)
			(end -0.12065 -0.305054)
			(stroke
				(width 0.1)
				(type default)
			)
			(layer "F.Fab")
		)
		(pad "1" smd circle
			(at -0.40005 0 180)
			(size 0 0)
			(layers "F.Cu" "F.Mask" "F.Paste")
			(net "PVCCD_HV_CPU0_ATSEN")
		)
		(pad "2" smd circle
			(at 0.40005 0 180)
			(size 0 0)
			(layers "F.Cu" "F.Mask" "F.Paste")
			(net "GND")
		)
	)
	(footprint ""
		(layer "F.Cu")
		(at 447.771774 -385.117594 180)
		(property "Reference" "PL65"
			(at -2.455926 5.957824 0)
			(unlocked yes)
			(layer "F.SilkS")
			(effects
				(font
					(size 0.7874 0.5842)
					(thickness 0.1524)
				)
				(justify left)
			)
		)
		(property "Value" ""
			(at 0 0 180)
			(layer "F.Fab")
			(effects
				(font
					(size 1.27 1.27)
				)
			)
		)
		(duplicate_pad_numbers_are_jumpers no)
		(fp_line
			(start 5.588 5.150104)
			(end 5.588 1.8034)
			(stroke
				(width 0.1524)
				(type default)
			)
			(layer "F.SilkS")
		)
		(fp_line
			(start 5.588 -1.8288)
			(end 5.588 -5.150104)
			(stroke
				(width 0.1524)
				(type default)
			)
			(layer "F.SilkS")
		)
		(fp_line
			(start 5.588 -5.150104)
			(end -5.588 -5.150104)
			(stroke
				(width 0.1524)
				(type default)
			)
			(layer "F.SilkS")
		)
		(fp_line
			(start -5.588 5.150104)
			(end 5.588 5.150104)
			(stroke
				(width 0.1524)
				(type default)
			)
			(layer "F.SilkS")
		)
		(fp_line
			(start -5.588 1.8288)
			(end -5.588 5.150104)
			(stroke
				(width 0.1524)
				(type default)
			)
			(layer "F.SilkS")
		)
		(fp_line
			(start -5.588 -5.150104)
			(end -5.588 -1.8542)
			(stroke
				(width 0.1524)
				(type default)
			)
			(layer "F.SilkS")
		)
		(fp_line
			(start 5.599938 5.150104)
			(end -5.599938 5.150104)
			(stroke
				(width 0.1)
				(type default)
			)
			(layer "F.Fab")
		)
		(fp_line
			(start 5.599938 -5.150104)
			(end 5.599938 5.150104)
			(stroke
				(width 0.1)
				(type default)
			)
			(layer "F.Fab")
		)
		(fp_line
			(start -5.599938 5.150104)
			(end -5.599938 -5.150104)
			(stroke
				(width 0.1)
				(type default)
			)
			(layer "F.Fab")
		)
		(fp_line
			(start -5.599938 -5.150104)
			(end 5.599938 -5.150104)
			(stroke
				(width 0.1)
				(type default)
			)
			(layer "F.Fab")
		)
		(pad "1" smd rect
			(at -4.338828 0 180)
			(size 3.302 3.302)
			(layers "F.Cu" "F.Mask" "F.Paste")
			(net "SW_P5V_AUX_SW")
		)
		(pad "2" smd rect
			(at 4.338828 0 180)
			(size 3.302 3.302)
			(layers "F.Cu" "F.Mask" "F.Paste")
			(net "P5V_AUX")
		)
	)
)
